#ISCELL
  mstr_misc dns *
  *
#ISCELL
  mstr_symbols cad_note *
  *
#ISCELL
  mstr_symbols design_note *
  *
#ISCELL
  mstr_symbols intel_corp_bpage *
  *
#CELL
  dev_discrete cap_a *
  page196_i102
#CELL
  mstr_discrete diode *
  page196_i103
#CELL
  mstr_vreg tps3700 *
  page196_i104
#CELL
  dev_discrete cap_a *
  page196_i105
#CELL
  mstr_discrete res *
  page196_i106
#ISCELL
  mstr_standard offpage *
  page196_i107
#ISCELL
  mstr_symbols gnd *
  page196_i108
#ISCELL
  mstr_symbols gnd *
  page196_i110
#ISCELL
  mstr_symbols p3v3_stby *
  page196_i111
#CELL
  mstr_discrete res *
  page196_i112
#CELL
  mstr_discrete res *
  page196_i114
#CELL
  mstr_discrete res *
  page196_i115
#ISCELL
  mstr_symbols p5v *
  page196_i116
#ISCELL
  mstr_symbols p12v *
  page196_i117
#ISCELL
  mstr_symbols gnd *
  page196_i118
#ISCELL
  mstr_symbols gnd *
  page196_i119
#CELL
  mstr_discrete res *
  page196_i120
#CELL
  mstr_discrete res *
  page196_i121
#CELL
  mstr_discrete res *
  page196_i122
#ISCELL
  mstr_symbols p3v3_stby *
  page196_i123
#ISCELL
  mstr_symbols gnd *
  page196_i125
#ISCELL
  mstr_symbols p3v3_stby *
  page196_i126
#ISCELL
  mstr_symbols p3v3_stby *
  page196_i127
#CELL
  mstr_discrete diode *
  page196_i128
#CELL
  mstr_discrete fet_n *
  page196_i129
#CELL
  mstr_discrete res *
  page196_i130
#ISCELL
  mstr_symbols gnd *
  page196_i43
#ISCELL
  mstr_standard offpage *
  page196_i45
#CELL
  mstr_discrete res *
  page196_i46
#CELL
  mstr_misc battery *
  page196_i47
#CELL
  mstr_discrete vert_batt_3pin *
  page196_i51
#ISCELL
  mstr_symbols gnd *
  page196_i52
#CELL
  mstr_discrete diode2a_dual *
  page196_i53
#ISCELL
  mstr_symbols p3v3_stby *
  page196_i54
#ISCELL
  mstr_symbols p3v3_stby *
  page196_i56
#ISCELL
  mstr_symbols p12v_stby *
  page196_i57
#ISCELL
  mstr_symbols p3v3_stby *
  page196_i58
#CELL
  mstr_discrete res *
  page196_i59
#CELL
  mstr_discrete cap *
  page196_i60
#ISCELL
  mstr_symbols gnd *
  page196_i61
#ISCELL
  mstr_symbols gnd *
  page196_i62
#ISCELL
  mstr_standard offpage *
  page196_i63
#ISCELL
  mstr_standard offpage *
  page196_i64
#CELL
  mstr_discrete res *
  page196_i65
#CELL
  mstr_discrete res *
  page196_i68
#ISCELL
  mstr_symbols p3v3_stby *
  page196_i69
#CELL
  mstr_analog adm1085 *
  page196_i70
#CELL
  mstr_discrete res *
  page196_i71
#CELL
  dev_discrete cap_a *
  page196_i72
#ISCELL
  mstr_symbols gnd *
  page196_i73
#CELL
  mstr_discrete res *
  page196_i74
#CELL
  mstr_discrete res *
  page196_i75
#ISCELL
  mstr_symbols gnd *
  page196_i76
#CELL
  mstr_analog adm809 *
  page196_i80
#CELL
  dev_discrete cap_a *
  page196_i81
#ISCELL
  mstr_symbols gnd *
  page196_i82
#ISCELL
  mstr_symbols p3v3 *
  page196_i83
#ISCELL
  mstr_standard offpage *
  page196_i88
#CELL
  mstr_analog adm809 *
  page196_i89
#CELL
  mstr_discrete res *
  page196_i90
#ISCELL
  mstr_standard offpage *
  page196_i91
#CELL
  dev_discrete cap_a *
  page196_i94
#ISCELL
  mstr_symbols gnd *
  page196_i95
#ISCELL
  mstr_standard offpage *
  page196_i96
#ISCELL
  mstr_symbols p3v3_rtc_stby *
  page196_i97
#ISCELL
  mstr_standard offpage *
  page196_i98
